# SCM (Grand Teton) — schematic netlist excerpt (pin names and nets, part order shuffled) for the footprints in the layout excerpt that follows; sources: Cadence DE-HDL packaged netlist, KiCad conversion of 12092022_DA0F0TMDCD0_F0T_Management_Board_D_brd_V3_OCP.brd

R698  Q_RES  0 5% CHIP  pkg 0402LF  page 47 : A = LED_POSTCODE_1 ; B = LED_POSTCODE_1_R1
R409  Q_RES  49.9 1% CHIP  pkg 0402LF  page 26 : A = SMB_TMP421_BMC_MM2_SDA ; B = SMB_BMC_MM2_SDA

(kicad_pcb
	(version 20260206)
	(generator "pcbnew")
	(generator_version "10.0")
	(general
		(thickness 1.6)
		(legacy_teardrops no)
	)
	(paper "A4")
	(title_block
		(title "12092022_DA0F0TMDCD0_F0T_Management_Board_D_brd_V3_OCP.brd")
		(comment 1 "Grand Teton / footprints 869-870 of 1440")
	)
	(layers
		(0 "F.Cu" signal "TOP")
		(4 "In1.Cu" signal "GND")
		(6 "In2.Cu" signal "IN1")
		(8 "In3.Cu" signal "GND1")
		(10 "In4.Cu" signal "IN2")
		(12 "In5.Cu" signal "VCC")
		(14 "In6.Cu" signal "VCC1")
		(16 "In7.Cu" signal "IN3")
		(18 "In8.Cu" signal "GND2")
		(20 "In9.Cu" signal "IN4")
		(22 "In10.Cu" signal "GND3")
		(2 "B.Cu" signal "BOTTOM")
		(9 "F.Adhes" user "F.Adhesive")
		(11 "B.Adhes" user "B.Adhesive")
		(13 "F.Paste" user "Package Geometry/Pastemask Top")
		(15 "B.Paste" user "Package Geometry/Pastemask Bottom")
		(5 "F.SilkS" user "Ref Des/Silkscreen Top")
		(7 "B.SilkS" user "Ref Des/Silkscreen Bottom")
		(1 "F.Mask" user "Board Geometry/Soldermask Top")
		(3 "B.Mask" user "Board Geometry/Soldermask Bottom")
		(17 "Dwgs.User" user "User.Drawings")
		(19 "Cmts.User" user "User.Comments")
		(21 "Eco1.User" user "User.Eco1")
		(23 "Eco2.User" user "User.Eco2")
		(25 "Edge.Cuts" user "Board Geometry/Outline")
		(27 "Margin" user)
		(31 "F.CrtYd" user "Package Geometry/Place Bound Top")
		(29 "B.CrtYd" user "Package Geometry/Place Bound Bottom")
		(35 "F.Fab" user "Ref Des/Assembly Top")
		(33 "B.Fab" user "Ref Des/Assembly Bottom")
	)
	(footprint ""
		(layer "B.Cu")
		(at 78.867 -29.718 -90)
		(property "Reference" "R698"
			(at 0 0 90)
			(layer "B.SilkS")
			(hide yes)
			(effects
				(font
					(size 1.27 1.27)
				)
				(justify mirror)
			)
		)
		(property "Value" ""
			(at 0 0 90)
			(layer "B.Fab")
			(effects
				(font
					(size 1.27 1.27)
				)
				(justify mirror)
			)
		)
		(duplicate_pad_numbers_are_jumpers no)
		(fp_line
			(start -0.7874 0.4064)
			(end 0.7874 0.4064)
			(stroke
				(width 0.1524)
				(type default)
			)
			(layer "B.SilkS")
		)
		(fp_line
			(start 0.7874 0.4064)
			(end 0.7874 -0.4064)
			(stroke
				(width 0.1524)
				(type default)
			)
			(layer "B.SilkS")
		)
		(fp_line
			(start -0.7874 -0.4064)
			(end -0.7874 0.4064)
			(stroke
				(width 0.1524)
				(type default)
			)
			(layer "B.SilkS")
		)
		(fp_line
			(start 0.7874 -0.4064)
			(end -0.7874 -0.4064)
			(stroke
				(width 0.1524)
				(type default)
			)
			(layer "B.SilkS")
		)
		(fp_line
			(start -0.67945 0.3048)
			(end -0.120396 0.3048)
			(stroke
				(width 0.1)
				(type default)
			)
			(layer "B.Fab")
		)
		(fp_line
			(start -0.120396 0.3048)
			(end -0.120396 0.2794)
			(stroke
				(width 0.1)
				(type default)
			)
			(layer "B.Fab")
		)
		(fp_line
			(start 0.12065 0.3048)
			(end 0.67945 0.3048)
			(stroke
				(width 0.1)
				(type default)
			)
			(layer "B.Fab")
		)
		(fp_line
			(start 0.67945 0.3048)
			(end 0.67945 -0.305054)
			(stroke
				(width 0.1)
				(type default)
			)
			(layer "B.Fab")
		)
		(fp_line
			(start -0.120396 0.2794)
			(end 0.12065 0.2794)
			(stroke
				(width 0.1)
				(type default)
			)
			(layer "B.Fab")
		)
		(fp_line
			(start 0.12065 0.2794)
			(end 0.12065 0.3048)
			(stroke
				(width 0.1)
				(type default)
			)
			(layer "B.Fab")
		)
		(fp_line
			(start -0.12065 -0.2794)
			(end -0.12065 -0.3048)
			(stroke
				(width 0.1)
				(type default)
			)
			(layer "B.Fab")
		)
		(fp_line
			(start 0.12065 -0.2794)
			(end -0.12065 -0.2794)
			(stroke
				(width 0.1)
				(type default)
			)
			(layer "B.Fab")
		)
		(fp_line
			(start -0.67945 -0.3048)
			(end -0.67945 0.3048)
			(stroke
				(width 0.1)
				(type default)
			)
			(layer "B.Fab")
		)
		(fp_line
			(start -0.12065 -0.3048)
			(end -0.67945 -0.3048)
			(stroke
				(width 0.1)
				(type default)
			)
			(layer "B.Fab")
		)
		(fp_line
			(start 0.12065 -0.305054)
			(end 0.12065 -0.2794)
			(stroke
				(width 0.1)
				(type default)
			)
			(layer "B.Fab")
		)
		(fp_line
			(start 0.67945 -0.305054)
			(end 0.12065 -0.305054)
			(stroke
				(width 0.1)
				(type default)
			)
			(layer "B.Fab")
		)
		(pad "1" smd circle
			(at 0.40005 0 90)
			(size 0 0)
			(layers "B.Cu" "B.Mask" "B.Paste")
			(net "LED_POSTCODE_1")
		)
		(pad "2" smd circle
			(at -0.40005 0 90)
			(size 0 0)
			(layers "B.Cu" "B.Mask" "B.Paste")
			(net "LED_POSTCODE_1_R1")
		)
	)
	(footprint ""
		(layer "B.Cu")
		(at 16.383 -17.907 -90)
		(property "Reference" "R409"
			(at 0 0 90)
			(layer "B.SilkS")
			(hide yes)
			(effects
				(font
					(size 1.27 1.27)
				)
				(justify mirror)
			)
		)
		(property "Value" ""
			(at 0 0 90)
			(layer "B.Fab")
			(effects
				(font
					(size 1.27 1.27)
				)
				(justify mirror)
			)
		)
		(duplicate_pad_numbers_are_jumpers no)
		(fp_line
			(start -0.7874 0.4064)
			(end 0.7874 0.4064)
			(stroke
				(width 0.1524)
				(type default)
			)
			(layer "B.SilkS")
		)
		(fp_line
			(start 0.7874 0.4064)
			(end 0.7874 -0.4064)
			(stroke
				(width 0.1524)
				(type default)
			)
			(layer "B.SilkS")
		)
		(fp_line
			(start -0.7874 -0.4064)
			(end -0.7874 0.4064)
			(stroke
				(width 0.1524)
				(type default)
			)
			(layer "B.SilkS")
		)
		(fp_line
			(start 0.7874 -0.4064)
			(end -0.7874 -0.4064)
			(stroke
				(width 0.1524)
				(type default)
			)
			(layer "B.SilkS")
		)
		(fp_line
			(start -0.67945 0.3048)
			(end -0.120396 0.3048)
			(stroke
				(width 0.1)
				(type default)
			)
			(layer "B.Fab")
		)
		(fp_line
			(start -0.120396 0.3048)
			(end -0.120396 0.2794)
			(stroke
				(width 0.1)
				(type default)
			)
			(layer "B.Fab")
		)
		(fp_line
			(start 0.12065 0.3048)
			(end 0.67945 0.3048)
			(stroke
				(width 0.1)
				(type default)
			)
			(layer "B.Fab")
		)
		(fp_line
			(start 0.67945 0.3048)
			(end 0.67945 -0.305054)
			(stroke
				(width 0.1)
				(type default)
			)
			(layer "B.Fab")
		)
		(fp_line
			(start -0.120396 0.2794)
			(end 0.12065 0.2794)
			(stroke
				(width 0.1)
				(type default)
			)
			(layer "B.Fab")
		)
		(fp_line
			(start 0.12065 0.2794)
			(end 0.12065 0.3048)
			(stroke
				(width 0.1)
				(type default)
			)
			(layer "B.Fab")
		)
		(fp_line
			(start -0.12065 -0.2794)
			(end -0.12065 -0.3048)
			(stroke
				(width 0.1)
				(type default)
			)
			(layer "B.Fab")
		)
		(fp_line
			(start 0.12065 -0.2794)
			(end -0.12065 -0.2794)
			(stroke
				(width 0.1)
				(type default)
			)
			(layer "B.Fab")
		)
		(fp_line
			(start -0.67945 -0.3048)
			(end -0.67945 0.3048)
			(stroke
				(width 0.1)
				(type default)
			)
			(layer "B.Fab")
		)
		(fp_line
			(start -0.12065 -0.3048)
			(end -0.67945 -0.3048)
			(stroke
				(width 0.1)
				(type default)
			)
			(layer "B.Fab")
		)
		(fp_line
			(start 0.12065 -0.305054)
			(end 0.12065 -0.2794)
			(stroke
				(width 0.1)
				(type default)
			)
			(layer "B.Fab")
		)
		(fp_line
			(start 0.67945 -0.305054)
			(end 0.12065 -0.305054)
			(stroke
				(width 0.1)
				(type default)
			)
			(layer "B.Fab")
		)
		(pad "1" smd circle
			(at 0.40005 0 90)
			(size 0 0)
			(layers "B.Cu" "B.Mask" "B.Paste")
			(net "SMB_TMP421_BMC_MM2_SDA")
		)
		(pad "2" smd circle
			(at -0.40005 0 90)
			(size 0 0)
			(layers "B.Cu" "B.Mask" "B.Paste")
			(net "SMB_BMC_MM2_SDA")
		)
	)
)
